# S9S_MB_2U (Grand Teton) — schematic netlist excerpt (pin names and nets, part order shuffled) for the footprints in the layout excerpt that follows; sources: Cadence DE-HDL packaged netlist, KiCad conversion of 03242023_DA0F0TMBIJ0_F0T_Motherboard_J_brd_V01_OCP.brd

J77  PICOPROBE_BXA  DELTA-L 4.0 EMPTY  pkg TRIANG_LAUNCH_3PXB  page 308
  \1_p\  = DELTA_L_85_10INCH_IN1_DP
  \2_n\  = DELTA_L_85_10INCH_IN1_DN
  \3_g\  = DELTA_L_GND_1

(kicad_pcb
	(version 20260206)
	(generator "pcbnew")
	(generator_version "10.0")
	(general
		(thickness 1.6)
		(legacy_teardrops no)
	)
	(paper "A4")
	(title_block
		(title "03242023_DA0F0TMBIJ0_F0T_Motherboard_J_brd_V01_OCP.brd")
		(comment 1 "Grand Teton / footprints 250-250 of 6105")
	)
	(layers
		(0 "F.Cu" signal "TOP")
		(4 "In1.Cu" signal "GND")
		(6 "In2.Cu" signal "IN1")
		(8 "In3.Cu" signal "GND1")
		(10 "In4.Cu" signal "IN2")
		(12 "In5.Cu" signal "GND2")
		(14 "In6.Cu" signal "IN3")
		(16 "In7.Cu" signal "GND3")
		(18 "In8.Cu" signal "VCC")
		(20 "In9.Cu" signal "VCC1")
		(22 "In10.Cu" signal "GND4")
		(24 "In11.Cu" signal "IN4")
		(26 "In12.Cu" signal "GND5")
		(28 "In13.Cu" signal "IN5")
		(30 "In14.Cu" signal "GND6")
		(32 "In15.Cu" signal "IN6")
		(34 "In16.Cu" signal "GND7")
		(2 "B.Cu" signal "BOTTOM")
		(9 "F.Adhes" user "F.Adhesive")
		(11 "B.Adhes" user "B.Adhesive")
		(13 "F.Paste" user "Package Geometry/Pastemask Top")
		(15 "B.Paste" user "Package Geometry/Pastemask Bottom")
		(5 "F.SilkS" user "Ref Des/Silkscreen Top")
		(7 "B.SilkS" user "Ref Des/Silkscreen Bottom")
		(1 "F.Mask" user "Board Geometry/Soldermask Top")
		(3 "B.Mask" user "Board Geometry/Soldermask Bottom")
		(17 "Dwgs.User" user "User.Drawings")
		(19 "Cmts.User" user "User.Comments")
		(21 "Eco1.User" user "User.Eco1")
		(23 "Eco2.User" user "User.Eco2")
		(25 "Edge.Cuts" user "Board Geometry/Outline")
		(27 "Margin" user)
		(31 "F.CrtYd" user "Package Geometry/Place Bound Top")
		(29 "B.CrtYd" user "Package Geometry/Place Bound Bottom")
		(35 "F.Fab" user "Ref Des/Assembly Top")
		(33 "B.Fab" user "Ref Des/Assembly Bottom")
	)
	(footprint ""
		(layer "F.Cu")
		(at 260.731508 0.383794)
		(property "Reference" "J77"
			(at -4.164838 0.886206 90)
			(unlocked yes)
			(layer "F.SilkS")
			(effects
				(font
					(size 0.7874 0.5842)
					(thickness 0.1524)
				)
				(justify left)
			)
		)
		(property "Value" ""
			(at 0 0 0)
			(layer "F.Fab")
			(effects
				(font
					(size 1.27 1.27)
				)
			)
		)
		(duplicate_pad_numbers_are_jumpers no)
		(fp_line
			(start -1.2192 -2.1082)
			(end 1.2192 -2.1082)
			(stroke
				(width 0.1524)
				(type default)
			)
			(layer "F.SilkS")
		)
		(fp_line
			(start -1.2192 2.1082)
			(end -1.2192 -2.1082)
			(stroke
				(width 0.1524)
				(type default)
			)
			(layer "F.SilkS")
		)
		(fp_line
			(start 1.2192 -2.1082)
			(end 1.2192 2.1082)
			(stroke
				(width 0.1524)
				(type default)
			)
			(layer "F.SilkS")
		)
		(fp_line
			(start 1.2192 2.1082)
			(end -1.2192 2.1082)
			(stroke
				(width 0.1524)
				(type default)
			)
			(layer "F.SilkS")
		)
		(pad "" np_thru_hole circle
			(at -2.8829 -1.27 270)
			(size 1.0414 1.0414)
			(drill 1.0414)
			(layers "*.Cu" "*.Mask")
			(clearance 0.381)
			(thermal_gap 0.381)
		)
		(pad "" np_thru_hole circle
			(at -2.8829 1.27 270)
			(size 1.0414 1.0414)
			(drill 1.0414)
			(layers "*.Cu" "*.Mask")
			(clearance 0.381)
			(thermal_gap 0.381)
		)
		(pad "" np_thru_hole circle
			(at 3.4671 -1.27 270)
			(size 1.0414 1.0414)
			(drill 1.0414)
			(layers "*.Cu" "*.Mask")
			(clearance 0.381)
			(thermal_gap 0.381)
		)
		(pad "" np_thru_hole circle
			(at 3.4671 1.27 270)
			(size 1.0414 1.0414)
			(drill 1.0414)
			(layers "*.Cu" "*.Mask")
			(clearance 0.381)
			(thermal_gap 0.381)
		)
		(pad "1" smd rect
			(at 0.8255 -0.249936 270)
			(size 0.3048 0.508)
			(layers "F.Cu" "F.Mask" "F.Paste")
			(net "DELTA_L_85_10INCH_IN1_DP")
		)
		(pad "2" smd rect
			(at 0.8255 0.249936 270)
			(size 0.3048 0.508)
			(layers "F.Cu" "F.Mask" "F.Paste")
			(net "DELTA_L_85_10INCH_IN1_DN")
		)
		(pad "3" smd circle
			(at 0 0)
			(size 0 0)
			(layers "F.Cu" "F.Mask" "F.Paste")
			(net "DELTA_L_GND_1")
		)
		(zone
			(layer "F.Cu")
			(hatch none 0.5)
			(connect_pads
				(clearance 0)
			)
			(min_thickness 0.25)
			(keepout
				(tracks not_allowed)
				(vias allowed)
				(pads allowed)
				(copperpour not_allowed)
				(footprints allowed)
			)
			(placement
				(enabled no)
				(sheetname "")
			)
			(fill
				(thermal_gap 0.5)
				(thermal_bridge_width 0.5)
				(island_removal_mode 0)
			)
			(polygon
				(pts
					(xy 261.849108 -0.164846) (xy 261.849108 -0.069342) (xy 261.252208 -0.069342) (xy 261.252208 0.337058)
					(xy 261.849108 0.337058) (xy 261.849108 0.43053) (xy 261.252208 0.43053) (xy 261.252208 0.83693)
					(xy 261.849108 0.83693) (xy 261.849108 0.932434) (xy 261.150608 0.932434) (xy 261.150608 -0.164846)
				)
			)
		)
		(zone
			(layers "F.Cu" "B.Cu" "In1.Cu" "In2.Cu" "In3.Cu" "In4.Cu" "In5.Cu" "In6.Cu"
				"In7.Cu" "In8.Cu" "In9.Cu" "In10.Cu" "In11.Cu" "In12.Cu" "In13.Cu" "In14.Cu"
				"In15.Cu" "In16.Cu"
			)
			(hatch none 0.5)
			(connect_pads
				(clearance 0)
			)
			(min_thickness 0.25)
			(keepout
				(tracks not_allowed)
				(vias allowed)
				(pads allowed)
				(copperpour not_allowed)
				(footprints allowed)
			)
			(placement
				(enabled no)
				(sheetname "")
			)
			(fill
				(thermal_gap 0.5)
				(thermal_bridge_width 0.5)
				(island_removal_mode 0)
			)
			(polygon
				(pts
					(arc
						(start 258.775708 -0.886206)
						(mid 256.921508 -0.886206)
						(end 258.775708 -0.886206)
					)
				)
			)
		)
		(zone
			(layers "F.Cu" "B.Cu" "In1.Cu" "In2.Cu" "In3.Cu" "In4.Cu" "In5.Cu" "In6.Cu"
				"In7.Cu" "In8.Cu" "In9.Cu" "In10.Cu" "In11.Cu" "In12.Cu" "In13.Cu" "In14.Cu"
				"In15.Cu" "In16.Cu"
			)
			(hatch none 0.5)
			(connect_pads
				(clearance 0)
			)
			(min_thickness 0.25)
			(keepout
				(tracks not_allowed)
				(vias allowed)
				(pads allowed)
				(copperpour not_allowed)
				(footprints allowed)
			)
			(placement
				(enabled no)
				(sheetname "")
			)
			(fill
				(thermal_gap 0.5)
				(thermal_bridge_width 0.5)
				(island_removal_mode 0)
			)
			(polygon
				(pts
					(arc
						(start 258.775708 1.653794)
						(mid 256.921508 1.653794)
						(end 258.775708 1.653794)
					)
				)
			)
		)
		(zone
			(layers "F.Cu" "B.Cu" "In1.Cu" "In2.Cu" "In3.Cu" "In4.Cu" "In5.Cu" "In6.Cu"
				"In7.Cu" "In8.Cu" "In9.Cu" "In10.Cu" "In11.Cu" "In12.Cu" "In13.Cu" "In14.Cu"
				"In15.Cu" "In16.Cu"
			)
			(hatch none 0.5)
			(connect_pads
				(clearance 0)
			)
			(min_thickness 0.25)
			(keepout
				(tracks not_allowed)
				(vias allowed)
				(pads allowed)
				(copperpour not_allowed)
				(footprints allowed)
			)
			(placement
				(enabled no)
				(sheetname "")
			)
			(fill
				(thermal_gap 0.5)
				(thermal_bridge_width 0.5)
				(island_removal_mode 0)
			)
			(polygon
				(pts
					(arc
						(start 265.125708 -0.886206)
						(mid 263.271508 -0.886206)
						(end 265.125708 -0.886206)
					)
				)
			)
		)
		(zone
			(layers "F.Cu" "B.Cu" "In1.Cu" "In2.Cu" "In3.Cu" "In4.Cu" "In5.Cu" "In6.Cu"
				"In7.Cu" "In8.Cu" "In9.Cu" "In10.Cu" "In11.Cu" "In12.Cu" "In13.Cu" "In14.Cu"
				"In15.Cu" "In16.Cu"
			)
			(hatch none 0.5)
			(connect_pads
				(clearance 0)
			)
			(min_thickness 0.25)
			(keepout
				(tracks not_allowed)
				(vias allowed)
				(pads allowed)
				(copperpour not_allowed)
				(footprints allowed)
			)
			(placement
				(enabled no)
				(sheetname "")
			)
			(fill
				(thermal_gap 0.5)
				(thermal_bridge_width 0.5)
				(island_removal_mode 0)
			)
			(polygon
				(pts
					(arc
						(start 265.125708 1.653794)
						(mid 263.271508 1.653794)
						(end 265.125708 1.653794)
					)
				)
			)
		)
	)
)
